FILE_TYPE = MULTI_PHYS_TABLE;

PART 'BC847BPN'

{========================================================================================}
:VALUE      | PART_TYPE | MATERIAL | PART_NUMBER    = STANDARD | LIFECYCLE          | PART_NUMBER   | JEDEC_TYPE | DESCRIPTION                         | MANUFTR | MANUF_PN   | RD_CMPLS_LVL | CMPLS_LVL | CLASS | DIP_SMD | FP_ECN | FROM_PJ    | DATA               | EE_CHECK_LIST | STATUS | PSL | PREFERENCE | CREATOR | CREATEDAY  | ESD_CDM | ESD_HBM | ESD_MM | MSD | PIN_LENGTH_LONG_PIN | PIN_LENGTH_SHORT_PIN ;
{========================================================================================}
 'BC847BPN' | 'SMLF'    | 'IC'     | 'BA008470026'(!) = ''       | ''               | 'BA008470026' |'SOT363XB'| 'TRANS SMD BC847BPN(45V,0.1A,0.3W)' | 'NXE'   | 'BC847BPN' | 'EP(V1)'     | ''        | 'IC'  | ''      | ''     | 'F0T-IVES' | 'NXE_BC847BPN.pdf' | ''            | ''     | ''  | ''         | ''      | '20221208' | ''      | ''      | ''     | ''  | '0 MILS'            | '0 MILS'            
 'BC847BPN' | 'SMLF'    | 'EMPTY'  | 'BA008470026'(!) = ''       | ''               | 'BA008470026' |'SOT363XB'| 'TRANS SMD BC847BPN(45V,0.1A,0.3W)' | 'NXE'   | 'BC847BPN' | 'EP(V1)'     | ''        | 'IC'  | ''      | ''     | 'F0T-IVES' | 'NXE_BC847BPN.pdf' | ''            | ''     | ''  | ''         | ''      | '20221208' | ''      | ''      | ''     | ''  | '0 MILS'            | '0 MILS'            

END_PART

END.

